# S9S_MB_2U (Grand Teton) — schematic parts with pin connectivity, parts 1595–1595 of 6093; source: Cadence DE-HDL packaged netlist (pstxprt.dat, pstxnet.dat, pstchip.dat)

J2  SCONN288_ADR50017P087CC  SCONN288_ADR50017-P087CC IO  pkg DDR288S_1-1VXB  page 83
  1  VIN_BULK0  POWER  = P12V_S3_AUX_CPU0_NVDIMM
  2  RFU0  TRI  = TP_CHA_CPU0_DIMM2_FRU_0
  3  VIN_MGMT  POWER  = P3V3_AUX
  4  HSCL  IN  = I3C_SPD_DDRABCD_CPU0_LVC1_SCL_1
  5  HSDA  BI  = I3C_SPD_DDRABCD_CPU0_LVC1_SDA
  6  VSS0  POWER  = GND
  7  DQ0_A  BI  = M_A_CPU0_SA_DQ<0>
  8  VSS1  POWER  = GND
  9  DQ1_A  BI  = M_A_CPU0_SA_DQ<1>
  10  VSS2  POWER  = GND
  11  DQS0_A_T  BI  = M_A_CPU0_SA_DQS_DP<0>
  12  DQS0_A_C  BI  = M_A_CPU0_SA_DQS_DN<0>
  13  VSS3  POWER  = GND
  14  DQ4_A  BI  = M_A_CPU0_SA_DQ<4>
  15  VSS4  POWER  = GND
  16  DQ5_A  BI  = M_A_CPU0_SA_DQ<5>
  17  VSS5  POWER  = GND
  18  DQ8_A  BI  = M_A_CPU0_SA_DQ<8>
  19  VSS6  POWER  = GND
  20  DQ9_A  BI  = M_A_CPU0_SA_DQ<9>
  21  VSS7  POWER  = GND
  22  DQS1_A_T  BI  = M_A_CPU0_SA_DQS_DP<1>
  23  DQS1_A_C  BI  = M_A_CPU0_SA_DQS_DN<1>
  24  VSS8  POWER  = GND
  25  DQ12_A  BI  = M_A_CPU0_SA_DQ<12>
  26  VSS9  POWER  = GND
  27  DQ13_A  BI  = M_A_CPU0_SA_DQ<13>
  28  VSS10  POWER  = GND
  29  DQ16_A  BI  = M_A_CPU0_SA_DQ<16>
  30  VSS11  POWER  = GND
  31  DQ17_A  BI  = M_A_CPU0_SA_DQ<17>
  32  VSS12  POWER  = GND
  33  DQS2_A_T  BI  = M_A_CPU0_SA_DQS_DP<2>
  34  DQS2_A_C  BI  = M_A_CPU0_SA_DQS_DN<2>
  35  VSS13  POWER  = GND
  36  DQ20_A  BI  = M_A_CPU0_SA_DQ<20>
  37  VSS14  POWER  = GND
  38  DQ21_A  BI  = M_A_CPU0_SA_DQ<21>
  39  VSS15  POWER  = GND
  40  DQ24_A  BI  = M_A_CPU0_SA_DQ<24>
  41  VSS16  POWER  = GND
  42  DQ25_A  BI  = M_A_CPU0_SA_DQ<25>
  43  VSS17  POWER  = GND
  44  DQS3_A_T  BI  = M_A_CPU0_SA_DQS_DP<3>
  45  DQS3_A_C  BI  = M_A_CPU0_SA_DQS_DN<3>
  46  VSS18  POWER  = GND
  47  DQ28_A  BI  = M_A_CPU0_SA_DQ<28>
  48  VSS19  POWER  = GND
  49  DQ29_A  BI  = M_A_CPU0_SA_DQ<29>
  50  VSS20  POWER  = GND
  51  CB0_A  BI  = M_A_CPU0_SA_CB<0>
  52  VSS21  POWER  = GND
  53  CB1_A  BI  = M_A_CPU0_SA_CB<1>
  54  VSS22  POWER  = GND
  55  DQS4_A_T  BI  = M_A_CPU0_SA_DQS_DP<4>
  56  DQS4_A_C  BI  = M_A_CPU0_SA_DQS_DN<4>
  57  VSS23  POWER  = GND
  58  CB4_A  BI  = M_A_CPU0_SA_CB<4>
  59  VSS24  POWER  = GND
  60  CB5_A  BI  = M_A_CPU0_SA_CB<5>
  61  VSS25  POWER  = GND
  62  ALERT_N  OUT  = M_A_CPU0_ALERT_N
  63  VSS26  POWER  = GND
  64  CS0_A_N  IN  = M_A_CPU0_SA_CS_N<2>
  65  VSS27  POWER  = GND
  66  CA0_A  IN  = M_A_CPU0_SA_CA<0>
  67  VSS28  POWER  = GND
  68  CA2_A  IN  = M_A_CPU0_SA_CA<2>
  69  VSS29  POWER  = GND
  70  CA4_A  IN  = M_A_CPU0_SA_CA<4>
  71  VSS30  POWER  = GND
  72  CA6_A  IN  = M_A_CPU0_SA_CA<6>
  73  VSS31  POWER  = GND
  74  PAR_A  IN  = M_A_CPU0_SA_PAR
  75  VSS32  POWER  = GND
  76  CA0_B  IN  = M_A_CPU0_SB_CA<0>
  77  VSS33  POWER  = GND
  78  CA2_B  IN  = M_A_CPU0_SB_CA<2>
  79  VSS34  POWER  = GND
  80  CA4_B  IN  = M_A_CPU0_SB_CA<4>
  81  VSS35  POWER  = GND
  82  CA6_B  IN  = M_A_CPU0_SB_CA<6>
  83  VSS36  POWER  = GND
  84  CS0_B_N  IN  = M_A_CPU0_SB_CS_N<2>
  85  VSS37  POWER  = GND
  86  \lbd||rsp_a_n\  OUT  = M_A_CPU0_SA_RSP<1>
  87  \lbs||rsp_b_n\  OUT  = M_A_CPU0_SB_RSP<1>
  88  VSS38  POWER  = GND
  89  CB4_B  BI  = M_A_CPU0_SB_CB<4>
  90  VSS39  POWER  = GND
  91  CB5_B  BI  = M_A_CPU0_SB_CB<5>
  92  VSS40  POWER  = GND
  93  \dqs9_b_t||tdqs9_b_t||dbi4_b_n\  BI  = M_A_CPU0_SB_DQS_DP<9>
  94  \dqs9_b_c||tdqs9_b_c\  BI  = M_A_CPU0_SB_DQS_DN<9>
  95  VSS41  POWER  = GND
  96  CB0_B  BI  = M_A_CPU0_SB_CB<0>
  97  VSS42  POWER  = GND
  98  CB1_B  BI  = M_A_CPU0_SB_CB<1>
  99  VSS43  POWER  = GND
  100  DQ0_B  BI  = M_A_CPU0_SB_DQ<0>
  101  VSS44  POWER  = GND
  102  DQ1_B  BI  = M_A_CPU0_SB_DQ<1>
  103  VSS45  POWER  = GND
  104  DQS0_B_T  BI  = M_A_CPU0_SB_DQS_DP<0>
  105  DQS0_B_C  BI  = M_A_CPU0_SB_DQS_DN<0>
  106  VSS46  POWER  = GND
  107  DQ4_B  BI  = M_A_CPU0_SB_DQ<4>
  108  VSS47  POWER  = GND
  109  DQ5_B  BI  = M_A_CPU0_SB_DQ<5>
  110  VSS48  POWER  = GND
  111  DQ8_B  BI  = M_A_CPU0_SB_DQ<8>
  112  VSS49  POWER  = GND
  113  DQ9_B  BI  = M_A_CPU0_SB_DQ<9>
  114  VSS50  POWER  = GND
  115  DQS1_B_T  BI  = M_A_CPU0_SB_DQS_DP<1>
  116  DQS1_B_C  BI  = M_A_CPU0_SB_DQS_DN<1>
  117  VSS51  POWER  = GND
  118  DQ12_B  BI  = M_A_CPU0_SB_DQ<12>
  119  VSS52  POWER  = GND
  120  DQ13_B  BI  = M_A_CPU0_SB_DQ<13>
  121  VSS53  POWER  = GND
  122  DQ16_B  BI  = M_A_CPU0_SB_DQ<16>
  123  VSS54  POWER  = GND
  124  DQ17_B  BI  = M_A_CPU0_SB_DQ<17>
  125  VSS55  POWER  = GND
  126  DQS2_B_T  BI  = M_A_CPU0_SB_DQS_DP<2>
  127  DQS2_B_C  BI  = M_A_CPU0_SB_DQS_DN<2>
  128  VSS56  POWER  = GND
  129  DQ20_B  BI  = M_A_CPU0_SB_DQ<20>
  130  VSS57  POWER  = GND
  131  DQ21_B  BI  = M_A_CPU0_SB_DQ<21>
  132  VSS58  POWER  = GND
  133  DQ24_B  BI  = M_A_CPU0_SB_DQ<24>
  134  VSS59  POWER  = GND
  135  DQ25_B  BI  = M_A_CPU0_SB_DQ<25>
  136  VSS60  POWER  = GND
  137  DQS3_B_T  BI  = M_A_CPU0_SB_DQS_DP<3>
  138  DQS3_B_C  BI  = M_A_CPU0_SB_DQS_DN<3>
  139  VSS61  POWER  = GND
  140  DQ28_B  BI  = M_A_CPU0_SB_DQ<28>
  141  VSS62  POWER  = GND
  142  DQ29_B  BI  = M_A_CPU0_SB_DQ<29>
  143  VSS63  POWER  = GND
  144  RFU1  TRI  = TP_CHA_CPU0_DIMM2_FRU_1
  145  VIN_BULK1  POWER  = P12V_S3_AUX_CPU0_NVDIMM
  146  VIN_BULK2  POWER  = P12V_S3_AUX_CPU0_NVDIMM
  147  \pwr_good||fail_n\  BI  = PWRGD_CHA_CPU0_DIMM2
  148  HSA  IN  = PD_CHA_CPU0_DIMM2_SAA
  149  RFU2  TRI  = TP_CHA_CPU0_DIMM2_FRU_2
  150  RFU3  TRI  = TP_CHA_CPU0_DIMM2_FRU_3
  151  VSS64  POWER  = GND
  152  DQ2_A  BI  = M_A_CPU0_SA_DQ<2>
  153  VSS65  POWER  = GND
  154  DQ3_A  BI  = M_A_CPU0_SA_DQ<3>
  155  VSS66  POWER  = GND
  156  \dqs5_a_c||tdqs5_a_c||dqs5_a_t||tdqs5_a_t\  BI  = M_A_CPU0_SA_DQS_DN<5>
  157  \dqs5_a_t||tdqs5_a_t\  BI  = M_A_CPU0_SA_DQS_DP<5>
  158  VSS67  POWER  = GND
  159  DQ6_A  BI  = M_A_CPU0_SA_DQ<6>
  160  VSS68  POWER  = GND
  161  DQ7_A  BI  = M_A_CPU0_SA_DQ<7>
  162  VSS69  POWER  = GND
  163  DQ10_A  BI  = M_A_CPU0_SA_DQ<10>
  164  VSS70  POWER  = GND
  165  DQ11_A  BI  = M_A_CPU0_SA_DQ<11>
  166  VSS71  POWER  = GND
  167  \dqs6_a_c||tdqs6_a_c||dqs6_a_t||tdqs6_a_t\  BI  = M_A_CPU0_SA_DQS_DN<6>
  168  \dqs6_a_t||tdqs6_a_t\  BI  = M_A_CPU0_SA_DQS_DP<6>
  169  VSS72  POWER  = GND
  170  DQ14_A  BI  = M_A_CPU0_SA_DQ<14>
  171  VSS73  POWER  = GND
  172  DQ15_A  BI  = M_A_CPU0_SA_DQ<15>
  173  VSS74  POWER  = GND
  174  DQ18_A  BI  = M_A_CPU0_SA_DQ<18>
  175  VSS75  POWER  = GND
  176  DQ19_A  BI  = M_A_CPU0_SA_DQ<19>
  177  VSS76  POWER  = GND
  178  \dqs7_a_c||tdqs7_a_c\  BI  = M_A_CPU0_SA_DQS_DN<7>
  179  \dqs7_a_t||tdqs7_a_t\  BI  = M_A_CPU0_SA_DQS_DP<7>
  180  VSS77  POWER  = GND
  181  DQ22_A  BI  = M_A_CPU0_SA_DQ<22>
  182  VSS78  POWER  = GND
  183  DQ23_A  BI  = M_A_CPU0_SA_DQ<23>
  184  VSS79  POWER  = GND
  185  DQ26_A  BI  = M_A_CPU0_SA_DQ<26>
  186  VSS80  POWER  = GND
  187  DQ27_A  BI  = M_A_CPU0_SA_DQ<27>
  188  VSS81  POWER  = GND
  189  \dqs8_a_c||tdqs8_a_c\  BI  = M_A_CPU0_SA_DQS_DN<8>
  190  \dqs8_a_t||tdqs8_a_t\  BI  = M_A_CPU0_SA_DQS_DP<8>
  191  VSS82  POWER  = GND
  192  DQ30_A  BI  = M_A_CPU0_SA_DQ<30>
  193  VSS83  POWER  = GND
  194  DQ31_A  BI  = M_A_CPU0_SA_DQ<31>
  195  VSS84  POWER  = GND
  196  CB2_A  BI  = M_A_CPU0_SA_CB<2>
  197  VSS85  POWER  = GND
  198  CB3_A  BI  = M_A_CPU0_SA_CB<3>
  199  VSS86  POWER  = GND
  200  \dqs9_a_c||tdqs9_a_c\  BI  = M_A_CPU0_SA_DQS_DN<9>
  201  \dqs9_a_t||tdqs9_a_t\  BI  = M_A_CPU0_SA_DQS_DP<9>
  202  VSS87  POWER  = GND
  203  CB6_A  BI  = M_A_CPU0_SA_CB<6>
  204  VSS88  POWER  = GND
  205  CB7_A  BI  = M_A_CPU0_SA_CB<7>
  206  VSS89  POWER  = GND
  207  RESET_N  IN  = RST_M_AB_CPU0_FPGA_N
  208  VSS90  POWER  = GND
  209  CS1_A_N  IN  = M_A_CPU0_SA_CS_N<3>
  210  VSS91  POWER  = GND
  211  CA1_A  IN  = M_A_CPU0_SA_CA<1>
  212  VSS92  POWER  = GND
  213  CA3_A  IN  = M_A_CPU0_SA_CA<3>
  214  VSS93  POWER  = GND
  215  CA5_A  IN  = M_A_CPU0_SA_CA<5>
  216  VSS94  POWER  = GND
  217  CK_T  IN  = M_A_CPU0_CLK_DP<1>
  218  CK_C  IN  = M_A_CPU0_CLK_DN<1>
  219  VSS95  POWER  = GND
  220  RFU4  TRI  = TP_CHA_CPU0_DIMM2_FRU_4
  221  CA1_B  IN  = M_A_CPU0_SB_CA<1>
  222  VSS96  POWER  = GND
  223  CA3_B  IN  = M_A_CPU0_SB_CA<3>
  224  VSS97  POWER  = GND
  225  CA5_B  IN  = M_A_CPU0_SB_CA<5>
  226  VSS98  POWER  = GND
  227  PAR_B  IN  = M_A_CPU0_SB_PAR
  228  VSS99  POWER  = GND
  229  CS1_B_N  IN  = M_A_CPU0_SB_CS_N<3>
  230  VSS100  POWER  = GND
  231  RFU5  TRI  = TP_CHA_CPU0_DIMM2_FRU_5
  232  RFU6  TRI  = TP_CHA_CPU0_DIMM2_FRU_6
  233  VSS101  POWER  = GND
  234  CB6_B  BI  = M_A_CPU0_SB_CB<6>
  235  VSS102  POWER  = GND
  236  CB7_B  BI  = M_A_CPU0_SB_CB<7>
  237  VSS103  POWER  = GND
  238  DQS4_B_C  BI  = M_A_CPU0_SB_DQS_DN<4>
  239  DQS4_B_T  BI  = M_A_CPU0_SB_DQS_DP<4>
  240  VSS104  POWER  = GND
  241  CB2_B  BI  = M_A_CPU0_SB_CB<2>
  242  VSS105  POWER  = GND
  243  CB3_B  BI  = M_A_CPU0_SB_CB<3>
  244  VSS106  POWER  = GND
  245  DQ2_B  BI  = M_A_CPU0_SB_DQ<2>
  246  VSS107  POWER  = GND
  247  DQ3_B  BI  = M_A_CPU0_SB_DQ<3>
  248  VSS108  POWER  = GND
  249  \dqs5_b_c||tdqs5_b_c\  BI  = M_A_CPU0_SB_DQS_DN<5>
  250  \dqs5_b_t||tdqs5_b_t\  BI  = M_A_CPU0_SB_DQS_DP<5>
  251  VSS109  POWER  = GND
  252  DQ6_B  BI  = M_A_CPU0_SB_DQ<6>
  253  VSS110  POWER  = GND
  254  DQ7_B  BI  = M_A_CPU0_SB_DQ<7>
  255  VSS111  POWER  = GND
  256  DQ10_B  BI  = M_A_CPU0_SB_DQ<10>
  257  VSS112  POWER  = GND
  258  DQ11_B  BI  = M_A_CPU0_SB_DQ<11>
  259  VSS113  POWER  = GND
  260  \dqs6_b_c||tdqs6_b_c\  BI  = M_A_CPU0_SB_DQS_DN<6>
  261  \dqs6_b_t||tdqs6_b_t\  BI  = M_A_CPU0_SB_DQS_DP<6>
  262  VSS114  POWER  = GND
  263  DQ14_B  BI  = M_A_CPU0_SB_DQ<14>
  264  VSS115  POWER  = GND
  265  DQ15_B  BI  = M_A_CPU0_SB_DQ<15>
  266  VSS116  POWER  = GND
  267  DQ18_B  BI  = M_A_CPU0_SB_DQ<18>
  268  VSS117  POWER  = GND
  269  DQ19_B  BI  = M_A_CPU0_SB_DQ<19>
  270  VSS118  POWER  = GND
  271  \dqs7_b_c||tdqs7_b_c\  BI  = M_A_CPU0_SB_DQS_DN<7>
  272  \dqs7_b_t||tdqs7_b_t\  BI  = M_A_CPU0_SB_DQS_DP<7>
  273  VSS119  POWER  = GND
  274  DQ22_B  BI  = M_A_CPU0_SB_DQ<22>
  275  VSS120  POWER  = GND
  276  DQ23_B  BI  = M_A_CPU0_SB_DQ<23>
  277  VSS121  POWER  = GND
  278  DQ26_B  BI  = M_A_CPU0_SB_DQ<26>
  279  VSS122  POWER  = GND
  280  DQ27_B  BI  = M_A_CPU0_SB_DQ<27>
  281  VSS123  POWER  = GND
  282  \dqs8_b_c||tdqs8_b_c\  BI  = M_A_CPU0_SB_DQS_DN<8>
  283  \dqs8_b_t||tdqs8_b_t\  BI  = M_A_CPU0_SB_DQS_DP<8>
  284  VSS124  POWER  = GND
  285  DQ30_B  BI  = M_A_CPU0_SB_DQ<30>
  286  VSS125  POWER  = GND
  287  DQ31_B  BI  = M_A_CPU0_SB_DQ<31>
  288  VSS126  POWER  = GND
  G1  G1  POWER  = GND
  G2  G2  POWER  = GND
  G3  G3  POWER  = GND
